(kicad_pcb
	(version 20260206)
	(generator "pcbnew")
	(generator_version "10.0")
	(general
		(thickness 1.6)
		(legacy_teardrops no)
	)
	(paper "A4")
	(title_block
		(title "Wiwynn_Tioga_Pass_MB.brd")
		(comment 1 "Tioga Pass / footprint 4281 of 4770 (J9L2), pads 1-123 of 291")
	)
	(layers
		(0 "F.Cu" signal "TOP")
		(4 "In1.Cu" signal "L2GND")
		(6 "In2.Cu" signal "L3")
		(8 "In3.Cu" signal "L4GND")
		(10 "In4.Cu" signal "L5")
		(12 "In5.Cu" signal "L6GND")
		(14 "In6.Cu" signal "L7VCC")
		(16 "In7.Cu" signal "L8VCC")
		(18 "In8.Cu" signal "L9GND")
		(20 "In9.Cu" signal "L10")
		(22 "In10.Cu" signal "L11GND")
		(24 "In11.Cu" signal "L12")
		(26 "In12.Cu" signal "L13GND")
		(2 "B.Cu" signal "BOTTOM")
		(9 "F.Adhes" user "F.Adhesive")
		(11 "B.Adhes" user "B.Adhesive")
		(13 "F.Paste" user "Package Geometry/Pastemask Top")
		(15 "B.Paste" user "Package Geometry/Pastemask Bottom")
		(5 "F.SilkS" user "Ref Des/Silkscreen Top")
		(7 "B.SilkS" user "Ref Des/Silkscreen Bottom")
		(1 "F.Mask" user "Board Geometry/Soldermask Top")
		(3 "B.Mask" user "Board Geometry/Soldermask Bottom")
		(17 "Dwgs.User" user "User.Drawings")
		(19 "Cmts.User" user "User.Comments")
		(21 "Eco1.User" user "User.Eco1")
		(23 "Eco2.User" user "User.Eco2")
		(25 "Edge.Cuts" user "Board Geometry/Outline")
		(27 "Margin" user)
		(31 "F.CrtYd" user "Package Geometry/Place Bound Top")
		(29 "B.CrtYd" user "Package Geometry/Place Bound Bottom")
		(35 "F.Fab" user "Ref Des/Assembly Top")
		(33 "B.Fab" user "Ref Des/Assembly Bottom")
	)
	(footprint ""
		(layer "B.Cu")
		(at 29.699458 -142.477236 90)
		(property "Reference" "J9L2"
			(at 2.403348 38.118542 0)
			(unlocked yes)
			(layer "B.SilkS")
			(effects
				(font
					(size 0.7874 0.5842)
					(thickness 0.1524)
				)
				(justify left mirror)
			)
		)
		(property "Value" ""
			(at 0 0 90)
			(layer "B.Fab")
			(effects
				(font
					(size 1.27 1.27)
				)
				(justify mirror)
			)
		)
		(duplicate_pad_numbers_are_jumpers no)
		(pad "" thru_hole circle
			(at -2.29997 -5.649976 270)
			(size 2.8194 2.8194)
			(drill 2.4384)
			(layers "*.Cu" "*.Mask")
			(remove_unused_layers no)
			(clearance 0.127)
			(thermal_gap 0.127)
		)
		(pad "" thru_hole oval
			(at -2.29997 68.90004 270)
			(size 2.8194 1.5748)
			(drill oval 2.4384 1.1938)
			(layers "*.Cu" "*.Mask")
			(remove_unused_layers no)
			(clearance 0.127)
			(thermal_gap 0.127)
		)
		(pad "" thru_hole circle
			(at -2.29997 132.299964 270)
			(size 2.8194 2.8194)
			(drill 2.4384)
			(layers "*.Cu" "*.Mask")
			(remove_unused_layers no)
			(clearance 0.127)
			(thermal_gap 0.127)
		)
		(pad "1" smd rect
			(at 0 0 270)
			(size 1.8034 0.508)
			(layers "B.Cu" "B.Mask" "B.Paste")
			(net "P12V_NVDIMM_KLM")
		)
		(pad "2" smd rect
			(at 0 0.849884 270)
			(size 1.8034 0.508)
			(layers "B.Cu" "B.Mask" "B.Paste")
			(net "GND")
		)
		(pad "3" smd rect
			(at 0 1.700022 270)
			(size 1.8034 0.508)
			(layers "B.Cu" "B.Mask" "B.Paste")
			(net "M_L_DQ<4>")
		)
		(pad "4" smd rect
			(at 0 2.549906 270)
			(size 1.8034 0.508)
			(layers "B.Cu" "B.Mask" "B.Paste")
			(net "GND")
		)
		(pad "5" smd rect
			(at 0 3.400044 270)
			(size 1.8034 0.508)
			(layers "B.Cu" "B.Mask" "B.Paste")
			(net "M_L_DQ<0>")
		)
		(pad "6" smd rect
			(at 0 4.249928 270)
			(size 1.8034 0.508)
			(layers "B.Cu" "B.Mask" "B.Paste")
			(net "GND")
		)
		(pad "7" smd rect
			(at 0 5.100066 270)
			(size 1.8034 0.508)
			(layers "B.Cu" "B.Mask" "B.Paste")
			(net "M_L_DQS_DP<9>")
		)
		(pad "8" smd rect
			(at 0 5.94995 270)
			(size 1.8034 0.508)
			(layers "B.Cu" "B.Mask" "B.Paste")
			(net "M_L_DQS_DN<9>")
		)
		(pad "9" smd rect
			(at 0 6.800088 270)
			(size 1.8034 0.508)
			(layers "B.Cu" "B.Mask" "B.Paste")
			(net "GND")
		)
		(pad "10" smd rect
			(at 0 7.649972 270)
			(size 1.8034 0.508)
			(layers "B.Cu" "B.Mask" "B.Paste")
			(net "M_L_DQ<6>")
		)
		(pad "11" smd rect
			(at 0 8.50011 270)
			(size 1.8034 0.508)
			(layers "B.Cu" "B.Mask" "B.Paste")
			(net "GND")
		)
		(pad "12" smd rect
			(at 0 9.349994 270)
			(size 1.8034 0.508)
			(layers "B.Cu" "B.Mask" "B.Paste")
			(net "M_L_DQ<2>")
		)
		(pad "13" smd rect
			(at 0 10.199878 270)
			(size 1.8034 0.508)
			(layers "B.Cu" "B.Mask" "B.Paste")
			(net "GND")
		)
		(pad "14" smd rect
			(at 0 11.050016 270)
			(size 1.8034 0.508)
			(layers "B.Cu" "B.Mask" "B.Paste")
			(net "M_L_DQ<12>")
		)
		(pad "15" smd rect
			(at 0 11.8999 270)
			(size 1.8034 0.508)
			(layers "B.Cu" "B.Mask" "B.Paste")
			(net "GND")
		)
		(pad "16" smd rect
			(at 0 12.750038 270)
			(size 1.8034 0.508)
			(layers "B.Cu" "B.Mask" "B.Paste")
			(net "M_L_DQ<8>")
		)
		(pad "17" smd rect
			(at 0 13.599922 270)
			(size 1.8034 0.508)
			(layers "B.Cu" "B.Mask" "B.Paste")
			(net "GND")
		)
		(pad "18" smd rect
			(at 0 14.45006 270)
			(size 1.8034 0.508)
			(layers "B.Cu" "B.Mask" "B.Paste")
			(net "M_L_DQS_DP<10>")
		)
		(pad "19" smd rect
			(at 0 15.299944 270)
			(size 1.8034 0.508)
			(layers "B.Cu" "B.Mask" "B.Paste")
			(net "M_L_DQS_DN<10>")
		)
		(pad "20" smd rect
			(at 0 16.150082 270)
			(size 1.8034 0.508)
			(layers "B.Cu" "B.Mask" "B.Paste")
			(net "GND")
		)
		(pad "21" smd rect
			(at 0 16.999966 270)
			(size 1.8034 0.508)
			(layers "B.Cu" "B.Mask" "B.Paste")
			(net "M_L_DQ<14>")
		)
		(pad "22" smd rect
			(at 0 17.850104 270)
			(size 1.8034 0.508)
			(layers "B.Cu" "B.Mask" "B.Paste")
			(net "GND")
		)
		(pad "23" smd rect
			(at 0 18.699988 270)
			(size 1.8034 0.508)
			(layers "B.Cu" "B.Mask" "B.Paste")
			(net "M_L_DQ<10>")
		)
		(pad "24" smd rect
			(at 0 19.550126 270)
			(size 1.8034 0.508)
			(layers "B.Cu" "B.Mask" "B.Paste")
			(net "GND")
		)
		(pad "25" smd rect
			(at 0 20.40001 270)
			(size 1.8034 0.508)
			(layers "B.Cu" "B.Mask" "B.Paste")
			(net "M_L_DQ<20>")
		)
		(pad "26" smd rect
			(at 0 21.249894 270)
			(size 1.8034 0.508)
			(layers "B.Cu" "B.Mask" "B.Paste")
			(net "GND")
		)
		(pad "27" smd rect
			(at 0 22.100032 270)
			(size 1.8034 0.508)
			(layers "B.Cu" "B.Mask" "B.Paste")
			(net "M_L_DQ<16>")
		)
		(pad "28" smd rect
			(at 0 22.949916 270)
			(size 1.8034 0.508)
			(layers "B.Cu" "B.Mask" "B.Paste")
			(net "GND")
		)
		(pad "29" smd rect
			(at 0 23.800054 270)
			(size 1.8034 0.508)
			(layers "B.Cu" "B.Mask" "B.Paste")
			(net "M_L_DQS_DP<11>")
		)
		(pad "30" smd rect
			(at 0 24.649938 270)
			(size 1.8034 0.508)
			(layers "B.Cu" "B.Mask" "B.Paste")
			(net "M_L_DQS_DN<11>")
		)
		(pad "31" smd rect
			(at 0 25.500076 270)
			(size 1.8034 0.508)
			(layers "B.Cu" "B.Mask" "B.Paste")
			(net "GND")
		)
		(pad "32" smd rect
			(at 0 26.34996 270)
			(size 1.8034 0.508)
			(layers "B.Cu" "B.Mask" "B.Paste")
			(net "M_L_DQ<22>")
		)
		(pad "33" smd rect
			(at 0 27.200098 270)
			(size 1.8034 0.508)
			(layers "B.Cu" "B.Mask" "B.Paste")
			(net "GND")
		)
		(pad "34" smd rect
			(at 0 28.049982 270)
			(size 1.8034 0.508)
			(layers "B.Cu" "B.Mask" "B.Paste")
			(net "M_L_DQ<18>")
		)
		(pad "35" smd rect
			(at 0 28.90012 270)
			(size 1.8034 0.508)
			(layers "B.Cu" "B.Mask" "B.Paste")
			(net "GND")
		)
		(pad "36" smd rect
			(at 0 29.750004 270)
			(size 1.8034 0.508)
			(layers "B.Cu" "B.Mask" "B.Paste")
			(net "M_L_DQ<28>")
		)
		(pad "37" smd rect
			(at 0 30.599888 270)
			(size 1.8034 0.508)
			(layers "B.Cu" "B.Mask" "B.Paste")
			(net "GND")
		)
		(pad "38" smd rect
			(at 0 31.450026 270)
			(size 1.8034 0.508)
			(layers "B.Cu" "B.Mask" "B.Paste")
			(net "M_L_DQ<24>")
		)
		(pad "39" smd rect
			(at 0 32.29991 270)
			(size 1.8034 0.508)
			(layers "B.Cu" "B.Mask" "B.Paste")
			(net "GND")
		)
		(pad "40" smd rect
			(at 0 33.150048 270)
			(size 1.8034 0.508)
			(layers "B.Cu" "B.Mask" "B.Paste")
			(net "M_L_DQS_DP<12>")
		)
		(pad "41" smd rect
			(at 0 33.999932 270)
			(size 1.8034 0.508)
			(layers "B.Cu" "B.Mask" "B.Paste")
			(net "M_L_DQS_DN<12>")
		)
		(pad "42" smd rect
			(at 0 34.85007 270)
			(size 1.8034 0.508)
			(layers "B.Cu" "B.Mask" "B.Paste")
			(net "GND")
		)
		(pad "43" smd rect
			(at 0 35.699954 270)
			(size 1.8034 0.508)
			(layers "B.Cu" "B.Mask" "B.Paste")
			(net "M_L_DQ<30>")
		)
		(pad "44" smd rect
			(at 0 36.550092 270)
			(size 1.8034 0.508)
			(layers "B.Cu" "B.Mask" "B.Paste")
			(net "GND")
		)
		(pad "45" smd rect
			(at 0 37.399976 270)
			(size 1.8034 0.508)
			(layers "B.Cu" "B.Mask" "B.Paste")
			(net "M_L_DQ<26>")
		)
		(pad "46" smd rect
			(at 0 38.250114 270)
			(size 1.8034 0.508)
			(layers "B.Cu" "B.Mask" "B.Paste")
			(net "GND")
		)
		(pad "47" smd rect
			(at 0 39.099998 270)
			(size 1.8034 0.508)
			(layers "B.Cu" "B.Mask" "B.Paste")
			(net "M_L_ECC<4>")
		)
		(pad "48" smd rect
			(at 0 39.949882 270)
			(size 1.8034 0.508)
			(layers "B.Cu" "B.Mask" "B.Paste")
			(net "GND")
		)
		(pad "49" smd rect
			(at 0 40.80002 270)
			(size 1.8034 0.508)
			(layers "B.Cu" "B.Mask" "B.Paste")
			(net "M_L_ECC<0>")
		)
		(pad "50" smd rect
			(at 0 41.649904 270)
			(size 1.8034 0.508)
			(layers "B.Cu" "B.Mask" "B.Paste")
			(net "GND")
		)
		(pad "51" smd rect
			(at 0 42.500042 270)
			(size 1.8034 0.508)
			(layers "B.Cu" "B.Mask" "B.Paste")
			(net "M_L_DQS_DP<17>")
		)
		(pad "52" smd rect
			(at 0 43.349926 270)
			(size 1.8034 0.508)
			(layers "B.Cu" "B.Mask" "B.Paste")
			(net "M_L_DQS_DN<17>")
		)
		(pad "53" smd rect
			(at 0 44.200064 270)
			(size 1.8034 0.508)
			(layers "B.Cu" "B.Mask" "B.Paste")
			(net "GND")
		)
		(pad "54" smd rect
			(at 0 45.049948 270)
			(size 1.8034 0.508)
			(layers "B.Cu" "B.Mask" "B.Paste")
			(net "M_L_ECC<6>")
		)
		(pad "55" smd rect
			(at 0 45.900086 270)
			(size 1.8034 0.508)
			(layers "B.Cu" "B.Mask" "B.Paste")
			(net "GND")
		)
		(pad "56" smd rect
			(at 0 46.74997 270)
			(size 1.8034 0.508)
			(layers "B.Cu" "B.Mask" "B.Paste")
			(net "M_L_ECC<2>")
		)
		(pad "57" smd rect
			(at 0 47.600108 270)
			(size 1.8034 0.508)
			(layers "B.Cu" "B.Mask" "B.Paste")
			(net "GND")
		)
		(pad "58" smd rect
			(at 0 48.449992 270)
			(size 1.8034 0.508)
			(layers "B.Cu" "B.Mask" "B.Paste")
			(net "M_KLM_RST_N")
		)
		(pad "59" smd rect
			(at 0 49.299876 270)
			(size 1.8034 0.508)
			(layers "B.Cu" "B.Mask" "B.Paste")
			(net "PVDDQ_KLM")
		)
		(pad "60" smd rect
			(at 0 50.150014 270)
			(size 1.8034 0.508)
			(layers "B.Cu" "B.Mask" "B.Paste")
			(net "M_L_CKE<2>")
		)
		(pad "61" smd rect
			(at 0 50.999898 270)
			(size 1.8034 0.508)
			(layers "B.Cu" "B.Mask" "B.Paste")
			(net "PVDDQ_KLM")
		)
		(pad "62" smd rect
			(at 0 51.850036 270)
			(size 1.8034 0.508)
			(layers "B.Cu" "B.Mask" "B.Paste")
			(net "M_L_ACT_N")
		)
		(pad "63" smd rect
			(at 0 52.69992 270)
			(size 1.8034 0.508)
			(layers "B.Cu" "B.Mask" "B.Paste")
			(net "M_L_BG<0>")
		)
		(pad "64" smd rect
			(at 0 53.550058 270)
			(size 1.8034 0.508)
			(layers "B.Cu" "B.Mask" "B.Paste")
			(net "PVDDQ_KLM")
		)
		(pad "65" smd rect
			(at 0 54.399942 270)
			(size 1.8034 0.508)
			(layers "B.Cu" "B.Mask" "B.Paste")
			(net "M_L_MA<12>")
		)
		(pad "66" smd rect
			(at 0 55.25008 270)
			(size 1.8034 0.508)
			(layers "B.Cu" "B.Mask" "B.Paste")
			(net "M_L_MA<9>")
		)
		(pad "67" smd rect
			(at 0 56.099964 270)
			(size 1.8034 0.508)
			(layers "B.Cu" "B.Mask" "B.Paste")
			(net "PVDDQ_KLM")
		)
		(pad "68" smd rect
			(at 0 56.950102 270)
			(size 1.8034 0.508)
			(layers "B.Cu" "B.Mask" "B.Paste")
			(net "M_L_MA<8>")
		)
		(pad "69" smd rect
			(at 0 57.799986 270)
			(size 1.8034 0.508)
			(layers "B.Cu" "B.Mask" "B.Paste")
			(net "M_L_MA<6>")
		)
		(pad "70" smd rect
			(at 0 58.650124 270)
			(size 1.8034 0.508)
			(layers "B.Cu" "B.Mask" "B.Paste")
			(net "PVDDQ_KLM")
		)
		(pad "71" smd rect
			(at 0 59.500008 270)
			(size 1.8034 0.508)
			(layers "B.Cu" "B.Mask" "B.Paste")
			(net "M_L_MA<3>")
		)
		(pad "72" smd rect
			(at 0 60.349892 270)
			(size 1.8034 0.508)
			(layers "B.Cu" "B.Mask" "B.Paste")
			(net "M_L_MA<1>")
		)
		(pad "73" smd rect
			(at 0 61.20003 270)
			(size 1.8034 0.508)
			(layers "B.Cu" "B.Mask" "B.Paste")
			(net "PVDDQ_KLM")
		)
		(pad "74" smd rect
			(at 0 62.049914 270)
			(size 1.8034 0.508)
			(layers "B.Cu" "B.Mask" "B.Paste")
			(net "M_L_CLK_DP<2>")
		)
		(pad "75" smd rect
			(at 0 62.900052 270)
			(size 1.8034 0.508)
			(layers "B.Cu" "B.Mask" "B.Paste")
			(net "M_L_CLK_DN<2>")
		)
		(pad "76" smd rect
			(at 0 63.749936 270)
			(size 1.8034 0.508)
			(layers "B.Cu" "B.Mask" "B.Paste")
			(net "PVDDQ_KLM")
		)
		(pad "77" smd rect
			(at 0 64.600074 270)
			(size 1.8034 0.508)
			(layers "B.Cu" "B.Mask" "B.Paste")
			(net "PVTT_KLM")
		)
		(pad "78" smd rect
			(at 0 70.550024 270)
			(size 1.8034 0.508)
			(layers "B.Cu" "B.Mask" "B.Paste")
			(net "FM_DIMM_EVENT_COD_N")
		)
		(pad "79" smd rect
			(at 0 71.399908 270)
			(size 1.8034 0.508)
			(layers "B.Cu" "B.Mask" "B.Paste")
			(net "M_L_MA<0>")
		)
		(pad "80" smd rect
			(at 0 72.250046 270)
			(size 1.8034 0.508)
			(layers "B.Cu" "B.Mask" "B.Paste")
			(net "PVDDQ_KLM")
		)
		(pad "81" smd rect
			(at 0 73.09993 270)
			(size 1.8034 0.508)
			(layers "B.Cu" "B.Mask" "B.Paste")
			(net "M_L_BA<0>")
		)
		(pad "82" smd rect
			(at 0 73.950068 270)
			(size 1.8034 0.508)
			(layers "B.Cu" "B.Mask" "B.Paste")
			(net "M_L_MA<16>")
		)
		(pad "83" smd rect
			(at 0 74.799952 270)
			(size 1.8034 0.508)
			(layers "B.Cu" "B.Mask" "B.Paste")
			(net "PVDDQ_KLM")
		)
		(pad "84" smd rect
			(at 0 75.65009 270)
			(size 1.8034 0.508)
			(layers "B.Cu" "B.Mask" "B.Paste")
			(net "M_L_CS_N<4>")
		)
		(pad "85" smd rect
			(at 0 76.499974 270)
			(size 1.8034 0.508)
			(layers "B.Cu" "B.Mask" "B.Paste")
			(net "PVDDQ_KLM")
		)
		(pad "86" smd rect
			(at 0 77.350112 270)
			(size 1.8034 0.508)
			(layers "B.Cu" "B.Mask" "B.Paste")
			(net "M_L_MA<15>")
		)
		(pad "87" smd rect
			(at 0 78.199996 270)
			(size 1.8034 0.508)
			(layers "B.Cu" "B.Mask" "B.Paste")
			(net "M_L_ODT<2>")
		)
		(pad "88" smd rect
			(at 0 79.04988 270)
			(size 1.8034 0.508)
			(layers "B.Cu" "B.Mask" "B.Paste")
			(net "PVDDQ_KLM")
		)
		(pad "89" smd rect
			(at 0 79.900018 270)
			(size 1.8034 0.508)
			(layers "B.Cu" "B.Mask" "B.Paste")
			(net "M_L_CS_N<5>")
		)
		(pad "90" smd rect
			(at 0 80.749902 270)
			(size 1.8034 0.508)
			(layers "B.Cu" "B.Mask" "B.Paste")
			(net "PVDDQ_KLM")
		)
		(pad "91" smd rect
			(at 0 81.60004 270)
			(size 1.8034 0.508)
			(layers "B.Cu" "B.Mask" "B.Paste")
			(net "M_L_ODT<3>")
		)
		(pad "92" smd rect
			(at 0 82.449924 270)
			(size 1.8034 0.508)
			(layers "B.Cu" "B.Mask" "B.Paste")
			(net "PVDDQ_KLM")
		)
		(pad "93" smd rect
			(at 0 83.300062 270)
			(size 1.8034 0.508)
			(layers "B.Cu" "B.Mask" "B.Paste")
			(net "M_L_CS_N<6>")
		)
		(pad "94" smd rect
			(at 0 84.149946 270)
			(size 1.8034 0.508)
			(layers "B.Cu" "B.Mask" "B.Paste")
			(net "GND")
		)
		(pad "95" smd rect
			(at 0 85.000084 270)
			(size 1.8034 0.508)
			(layers "B.Cu" "B.Mask" "B.Paste")
			(net "M_L_DQ<36>")
		)
		(pad "96" smd rect
			(at 0 85.849968 270)
			(size 1.8034 0.508)
			(layers "B.Cu" "B.Mask" "B.Paste")
			(net "GND")
		)
		(pad "97" smd rect
			(at 0 86.700106 270)
			(size 1.8034 0.508)
			(layers "B.Cu" "B.Mask" "B.Paste")
			(net "M_L_DQ<32>")
		)
		(pad "98" smd rect
			(at 0 87.54999 270)
			(size 1.8034 0.508)
			(layers "B.Cu" "B.Mask" "B.Paste")
			(net "GND")
		)
		(pad "99" smd rect
			(at 0 88.399874 270)
			(size 1.8034 0.508)
			(layers "B.Cu" "B.Mask" "B.Paste")
			(net "M_L_DQS_DP<13>")
		)
		(pad "100" smd rect
			(at 0 89.250012 270)
			(size 1.8034 0.508)
			(layers "B.Cu" "B.Mask" "B.Paste")
			(net "M_L_DQS_DN<13>")
		)
		(pad "101" smd rect
			(at 0 90.099896 270)
			(size 1.8034 0.508)
			(layers "B.Cu" "B.Mask" "B.Paste")
			(net "GND")
		)
		(pad "102" smd rect
			(at 0 90.950034 270)
			(size 1.8034 0.508)
			(layers "B.Cu" "B.Mask" "B.Paste")
			(net "M_L_DQ<38>")
		)
		(pad "103" smd rect
			(at 0 91.799918 270)
			(size 1.8034 0.508)
			(layers "B.Cu" "B.Mask" "B.Paste")
			(net "GND")
		)
		(pad "104" smd rect
			(at 0 92.650056 270)
			(size 1.8034 0.508)
			(layers "B.Cu" "B.Mask" "B.Paste")
			(net "M_L_DQ<34>")
		)
		(pad "105" smd rect
			(at 0 93.49994 270)
			(size 1.8034 0.508)
			(layers "B.Cu" "B.Mask" "B.Paste")
			(net "GND")
		)
		(pad "106" smd rect
			(at 0 94.350078 270)
			(size 1.8034 0.508)
			(layers "B.Cu" "B.Mask" "B.Paste")
			(net "M_L_DQ<44>")
		)
		(pad "107" smd rect
			(at 0 95.199962 270)
			(size 1.8034 0.508)
			(layers "B.Cu" "B.Mask" "B.Paste")
			(net "GND")
		)
		(pad "108" smd rect
			(at 0 96.0501 270)
			(size 1.8034 0.508)
			(layers "B.Cu" "B.Mask" "B.Paste")
			(net "M_L_DQ<40>")
		)
		(pad "109" smd rect
			(at 0 96.899984 270)
			(size 1.8034 0.508)
			(layers "B.Cu" "B.Mask" "B.Paste")
			(net "GND")
		)
		(pad "110" smd rect
			(at 0 97.750122 270)
			(size 1.8034 0.508)
			(layers "B.Cu" "B.Mask" "B.Paste")
			(net "M_L_DQS_DP<14>")
		)
		(pad "111" smd rect
			(at 0 98.600006 270)
			(size 1.8034 0.508)
			(layers "B.Cu" "B.Mask" "B.Paste")
			(net "M_L_DQS_DN<14>")
		)
		(pad "112" smd rect
			(at 0 99.44989 270)
			(size 1.8034 0.508)
			(layers "B.Cu" "B.Mask" "B.Paste")
			(net "GND")
		)
		(pad "113" smd rect
			(at 0 100.300028 270)
			(size 1.8034 0.508)
			(layers "B.Cu" "B.Mask" "B.Paste")
			(net "M_L_DQ<46>")
		)
		(pad "114" smd rect
			(at 0 101.149912 270)
			(size 1.8034 0.508)
			(layers "B.Cu" "B.Mask" "B.Paste")
			(net "GND")
		)
		(pad "115" smd rect
			(at 0 102.00005 270)
			(size 1.8034 0.508)
			(layers "B.Cu" "B.Mask" "B.Paste")
			(net "M_L_DQ<42>")
		)
		(pad "116" smd rect
			(at 0 102.849934 270)
			(size 1.8034 0.508)
			(layers "B.Cu" "B.Mask" "B.Paste")
			(net "GND")
		)
		(pad "117" smd rect
			(at 0 103.700072 270)
			(size 1.8034 0.508)
			(layers "B.Cu" "B.Mask" "B.Paste")
			(net "M_L_DQ<52>")
		)
		(pad "118" smd rect
			(at 0 104.549956 270)
			(size 1.8034 0.508)
			(layers "B.Cu" "B.Mask" "B.Paste")
			(net "GND")
		)
		(pad "119" smd rect
			(at 0 105.400094 270)
			(size 1.8034 0.508)
			(layers "B.Cu" "B.Mask" "B.Paste")
			(net "M_L_DQ<48>")
		)
		(pad "120" smd rect
			(at 0 106.249978 270)
			(size 1.8034 0.508)
			(layers "B.Cu" "B.Mask" "B.Paste")
			(net "GND")
		)
	)
)
